# SCM (Grand Teton) — schematic netlist excerpt (pin names and nets, part order shuffled) for the footprints in the layout excerpt that follows; sources: Cadence DE-HDL packaged netlist, KiCad conversion of 12092022_DA0F0TMDCD0_F0T_Management_Board_D_brd_V3_OCP.brd

R530  Q_RES  100 1% CHIP  pkg 0402LF  page 54 : A = PWRGD_P3V3_RGM ; B = PWRGD_P3V3_RGM_R2

U12  MOSFET_N  BSS138K IC  pkg SMLF  page 22
  DRAIN  = RST_BMC_EXTRST_R1_N
  GATE  = RST_BMC_SELF_HW_D_C
  SOURCE  = GND

R431  Q_RES  100 1% EMPTY  pkg 0402LF  page 48 : A = FM_BMC_DISABLE ; B = GND

(kicad_pcb
	(version 20260206)
	(generator "pcbnew")
	(generator_version "10.0")
	(general
		(thickness 1.6)
		(legacy_teardrops no)
	)
	(paper "A4")
	(title_block
		(title "12092022_DA0F0TMDCD0_F0T_Management_Board_D_brd_V3_OCP.brd")
		(comment 1 "Grand Teton / footprints 458-460 of 1440")
	)
	(layers
		(0 "F.Cu" signal "TOP")
		(4 "In1.Cu" signal "GND")
		(6 "In2.Cu" signal "IN1")
		(8 "In3.Cu" signal "GND1")
		(10 "In4.Cu" signal "IN2")
		(12 "In5.Cu" signal "VCC")
		(14 "In6.Cu" signal "VCC1")
		(16 "In7.Cu" signal "IN3")
		(18 "In8.Cu" signal "GND2")
		(20 "In9.Cu" signal "IN4")
		(22 "In10.Cu" signal "GND3")
		(2 "B.Cu" signal "BOTTOM")
		(9 "F.Adhes" user "F.Adhesive")
		(11 "B.Adhes" user "B.Adhesive")
		(13 "F.Paste" user "Package Geometry/Pastemask Top")
		(15 "B.Paste" user "Package Geometry/Pastemask Bottom")
		(5 "F.SilkS" user "Ref Des/Silkscreen Top")
		(7 "B.SilkS" user "Ref Des/Silkscreen Bottom")
		(1 "F.Mask" user "Board Geometry/Soldermask Top")
		(3 "B.Mask" user "Board Geometry/Soldermask Bottom")
		(17 "Dwgs.User" user "User.Drawings")
		(19 "Cmts.User" user "User.Comments")
		(21 "Eco1.User" user "User.Eco1")
		(23 "Eco2.User" user "User.Eco2")
		(25 "Edge.Cuts" user "Board Geometry/Outline")
		(27 "Margin" user)
		(31 "F.CrtYd" user "Package Geometry/Place Bound Top")
		(29 "B.CrtYd" user "Package Geometry/Place Bound Bottom")
		(35 "F.Fab" user "Ref Des/Assembly Top")
		(33 "B.Fab" user "Ref Des/Assembly Bottom")
	)
	(footprint ""
		(layer "F.Cu")
		(at 73.152 -74.295 90)
		(property "Reference" "R431"
			(at 0 0 90)
			(layer "F.SilkS")
			(hide yes)
			(effects
				(font
					(size 1.27 1.27)
				)
			)
		)
		(property "Value" ""
			(at 0 0 90)
			(layer "F.Fab")
			(effects
				(font
					(size 1.27 1.27)
				)
			)
		)
		(duplicate_pad_numbers_are_jumpers no)
		(fp_line
			(start 0.7874 -0.4064)
			(end 0.7874 0.4064)
			(stroke
				(width 0.1524)
				(type default)
			)
			(layer "F.SilkS")
		)
		(fp_line
			(start -0.7874 -0.4064)
			(end 0.7874 -0.4064)
			(stroke
				(width 0.1524)
				(type default)
			)
			(layer "F.SilkS")
		)
		(fp_line
			(start 0.7874 0.4064)
			(end -0.7874 0.4064)
			(stroke
				(width 0.1524)
				(type default)
			)
			(layer "F.SilkS")
		)
		(fp_line
			(start -0.7874 0.4064)
			(end -0.7874 -0.4064)
			(stroke
				(width 0.1524)
				(type default)
			)
			(layer "F.SilkS")
		)
		(fp_line
			(start -0.12065 -0.305054)
			(end -0.12065 -0.2794)
			(stroke
				(width 0.1)
				(type default)
			)
			(layer "F.Fab")
		)
		(fp_line
			(start -0.67945 -0.305054)
			(end -0.12065 -0.305054)
			(stroke
				(width 0.1)
				(type default)
			)
			(layer "F.Fab")
		)
		(fp_line
			(start 0.67945 -0.3048)
			(end 0.67945 0.3048)
			(stroke
				(width 0.1)
				(type default)
			)
			(layer "F.Fab")
		)
		(fp_line
			(start 0.12065 -0.3048)
			(end 0.67945 -0.3048)
			(stroke
				(width 0.1)
				(type default)
			)
			(layer "F.Fab")
		)
		(fp_line
			(start 0.12065 -0.2794)
			(end 0.12065 -0.3048)
			(stroke
				(width 0.1)
				(type default)
			)
			(layer "F.Fab")
		)
		(fp_line
			(start -0.12065 -0.2794)
			(end 0.12065 -0.2794)
			(stroke
				(width 0.1)
				(type default)
			)
			(layer "F.Fab")
		)
		(fp_line
			(start 0.120396 0.2794)
			(end -0.12065 0.2794)
			(stroke
				(width 0.1)
				(type default)
			)
			(layer "F.Fab")
		)
		(fp_line
			(start -0.12065 0.2794)
			(end -0.12065 0.3048)
			(stroke
				(width 0.1)
				(type default)
			)
			(layer "F.Fab")
		)
		(fp_line
			(start 0.67945 0.3048)
			(end 0.120396 0.3048)
			(stroke
				(width 0.1)
				(type default)
			)
			(layer "F.Fab")
		)
		(fp_line
			(start 0.120396 0.3048)
			(end 0.120396 0.2794)
			(stroke
				(width 0.1)
				(type default)
			)
			(layer "F.Fab")
		)
		(fp_line
			(start -0.12065 0.3048)
			(end -0.67945 0.3048)
			(stroke
				(width 0.1)
				(type default)
			)
			(layer "F.Fab")
		)
		(fp_line
			(start -0.67945 0.3048)
			(end -0.67945 -0.305054)
			(stroke
				(width 0.1)
				(type default)
			)
			(layer "F.Fab")
		)
		(pad "1" smd circle
			(at -0.40005 0 90)
			(size 0 0)
			(layers "F.Cu" "F.Mask" "F.Paste")
			(net "FM_BMC_DISABLE")
		)
		(pad "2" smd circle
			(at 0.40005 0 90)
			(size 0 0)
			(layers "F.Cu" "F.Mask" "F.Paste")
			(net "GND")
		)
	)
	(footprint ""
		(layer "F.Cu")
		(at 31.115 -64.8208 -90)
		(property "Reference" "R530"
			(at 0 0 270)
			(layer "F.SilkS")
			(hide yes)
			(effects
				(font
					(size 1.27 1.27)
				)
			)
		)
		(property "Value" ""
			(at 0 0 270)
			(layer "F.Fab")
			(effects
				(font
					(size 1.27 1.27)
				)
			)
		)
		(duplicate_pad_numbers_are_jumpers no)
		(fp_line
			(start -0.7874 0.4064)
			(end -0.7874 -0.4064)
			(stroke
				(width 0.1524)
				(type default)
			)
			(layer "F.SilkS")
		)
		(fp_line
			(start 0.7874 0.4064)
			(end -0.7874 0.4064)
			(stroke
				(width 0.1524)
				(type default)
			)
			(layer "F.SilkS")
		)
		(fp_line
			(start -0.7874 -0.4064)
			(end 0.7874 -0.4064)
			(stroke
				(width 0.1524)
				(type default)
			)
			(layer "F.SilkS")
		)
		(fp_line
			(start 0.7874 -0.4064)
			(end 0.7874 0.4064)
			(stroke
				(width 0.1524)
				(type default)
			)
			(layer "F.SilkS")
		)
		(fp_line
			(start -0.67945 0.3048)
			(end -0.67945 -0.305054)
			(stroke
				(width 0.1)
				(type default)
			)
			(layer "F.Fab")
		)
		(fp_line
			(start -0.12065 0.3048)
			(end -0.67945 0.3048)
			(stroke
				(width 0.1)
				(type default)
			)
			(layer "F.Fab")
		)
		(fp_line
			(start 0.120396 0.3048)
			(end 0.120396 0.2794)
			(stroke
				(width 0.1)
				(type default)
			)
			(layer "F.Fab")
		)
		(fp_line
			(start 0.67945 0.3048)
			(end 0.120396 0.3048)
			(stroke
				(width 0.1)
				(type default)
			)
			(layer "F.Fab")
		)
		(fp_line
			(start -0.12065 0.2794)
			(end -0.12065 0.3048)
			(stroke
				(width 0.1)
				(type default)
			)
			(layer "F.Fab")
		)
		(fp_line
			(start 0.120396 0.2794)
			(end -0.12065 0.2794)
			(stroke
				(width 0.1)
				(type default)
			)
			(layer "F.Fab")
		)
		(fp_line
			(start -0.12065 -0.2794)
			(end 0.12065 -0.2794)
			(stroke
				(width 0.1)
				(type default)
			)
			(layer "F.Fab")
		)
		(fp_line
			(start 0.12065 -0.2794)
			(end 0.12065 -0.3048)
			(stroke
				(width 0.1)
				(type default)
			)
			(layer "F.Fab")
		)
		(fp_line
			(start 0.12065 -0.3048)
			(end 0.67945 -0.3048)
			(stroke
				(width 0.1)
				(type default)
			)
			(layer "F.Fab")
		)
		(fp_line
			(start 0.67945 -0.3048)
			(end 0.67945 0.3048)
			(stroke
				(width 0.1)
				(type default)
			)
			(layer "F.Fab")
		)
		(fp_line
			(start -0.67945 -0.305054)
			(end -0.12065 -0.305054)
			(stroke
				(width 0.1)
				(type default)
			)
			(layer "F.Fab")
		)
		(fp_line
			(start -0.12065 -0.305054)
			(end -0.12065 -0.2794)
			(stroke
				(width 0.1)
				(type default)
			)
			(layer "F.Fab")
		)
		(pad "1" smd circle
			(at -0.40005 0 270)
			(size 0 0)
			(layers "F.Cu" "F.Mask" "F.Paste")
			(net "PWRGD_P3V3_RGM")
		)
		(pad "2" smd circle
			(at 0.40005 0 270)
			(size 0 0)
			(layers "F.Cu" "F.Mask" "F.Paste")
			(net "PWRGD_P3V3_RGM_R2")
		)
	)
	(footprint ""
		(layer "F.Cu")
		(at 20.0025 -105.9942 180)
		(property "Reference" "U12"
			(at -1.1303 2.28473 0)
			(unlocked yes)
			(layer "F.SilkS")
			(effects
				(font
					(size 0.7874 0.5842)
					(thickness 0.1524)
				)
			)
		)
		(property "Value" ""
			(at 0 0 180)
			(layer "F.Fab")
			(effects
				(font
					(size 1.27 1.27)
				)
			)
		)
		(duplicate_pad_numbers_are_jumpers no)
		(fp_line
			(start 1.949958 1.610106)
			(end -1.949958 1.610106)
			(stroke
				(width 0.1524)
				(type default)
			)
			(layer "F.SilkS")
		)
		(fp_line
			(start 1.949958 -1.560068)
			(end 1.949958 1.610106)
			(stroke
				(width 0.1524)
				(type default)
			)
			(layer "F.SilkS")
		)
		(fp_line
			(start -1.949958 1.610106)
			(end -1.949958 -1.610106)
			(stroke
				(width 0.1524)
				(type default)
			)
			(layer "F.SilkS")
		)
		(fp_line
			(start -1.949958 -1.610106)
			(end 1.949958 -1.610106)
			(stroke
				(width 0.1524)
				(type default)
			)
			(layer "F.SilkS")
		)
		(fp_line
			(start 0.750062 1.560068)
			(end -0.750062 1.560068)
			(stroke
				(width 0.1)
				(type default)
			)
			(layer "F.Fab")
		)
		(fp_line
			(start 0.750062 -1.560068)
			(end 0.750062 1.560068)
			(stroke
				(width 0.1)
				(type default)
			)
			(layer "F.Fab")
		)
		(fp_line
			(start -0.750062 1.560068)
			(end -0.750062 -1.560068)
			(stroke
				(width 0.1)
				(type default)
			)
			(layer "F.Fab")
		)
		(fp_line
			(start -0.750062 -1.560068)
			(end 0.750062 -1.560068)
			(stroke
				(width 0.1)
				(type default)
			)
			(layer "F.Fab")
		)
		(pad "D" smd rect
			(at 1.100074 0 90)
			(size 1.016 1.4224)
			(layers "F.Cu" "F.Mask" "F.Paste")
			(net "RST_BMC_EXTRST_R1_N")
		)
		(pad "G" smd rect
			(at -1.100074 -0.94996 90)
			(size 1.016 1.4224)
			(layers "F.Cu" "F.Mask" "F.Paste")
			(net "RST_BMC_SELF_HW_D_C")
		)
		(pad "S" smd rect
			(at -1.100074 0.94996 90)
			(size 1.016 1.4224)
			(layers "F.Cu" "F.Mask" "F.Paste")
			(net "GND")
		)
	)
)
